# SCM (Grand Teton) — schematic netlist excerpt (pin names and nets, part order shuffled) for the footprints in the layout excerpt that follows; sources: Cadence DE-HDL packaged netlist, KiCad conversion of 12092022_DA0F0TMDCD0_F0T_Management_Board_D_brd_V3_OCP.brd

R334  Q_RES  120 1% CHIP  pkg 0402LF  page 20 : A = GND ; B = M_BMC_DDR4_MA<8>
R260  Q_RES  10K 1% CHIP  pkg 0402LF  page 27 : A = P3V3_AUX ; B = SMB_BMC_MM9_SCL

(kicad_pcb
	(version 20260206)
	(generator "pcbnew")
	(generator_version "10.0")
	(general
		(thickness 1.6)
		(legacy_teardrops no)
	)
	(paper "A4")
	(title_block
		(title "12092022_DA0F0TMDCD0_F0T_Management_Board_D_brd_V3_OCP.brd")
		(comment 1 "Grand Teton / footprints 855-856 of 1440")
	)
	(layers
		(0 "F.Cu" signal "TOP")
		(4 "In1.Cu" signal "GND")
		(6 "In2.Cu" signal "IN1")
		(8 "In3.Cu" signal "GND1")
		(10 "In4.Cu" signal "IN2")
		(12 "In5.Cu" signal "VCC")
		(14 "In6.Cu" signal "VCC1")
		(16 "In7.Cu" signal "IN3")
		(18 "In8.Cu" signal "GND2")
		(20 "In9.Cu" signal "IN4")
		(22 "In10.Cu" signal "GND3")
		(2 "B.Cu" signal "BOTTOM")
		(9 "F.Adhes" user "F.Adhesive")
		(11 "B.Adhes" user "B.Adhesive")
		(13 "F.Paste" user "Package Geometry/Pastemask Top")
		(15 "B.Paste" user "Package Geometry/Pastemask Bottom")
		(5 "F.SilkS" user "Ref Des/Silkscreen Top")
		(7 "B.SilkS" user "Ref Des/Silkscreen Bottom")
		(1 "F.Mask" user "Board Geometry/Soldermask Top")
		(3 "B.Mask" user "Board Geometry/Soldermask Bottom")
		(17 "Dwgs.User" user "User.Drawings")
		(19 "Cmts.User" user "User.Comments")
		(21 "Eco1.User" user "User.Eco1")
		(23 "Eco2.User" user "User.Eco2")
		(25 "Edge.Cuts" user "Board Geometry/Outline")
		(27 "Margin" user)
		(31 "F.CrtYd" user "Package Geometry/Place Bound Top")
		(29 "B.CrtYd" user "Package Geometry/Place Bound Bottom")
		(35 "F.Fab" user "Ref Des/Assembly Top")
		(33 "B.Fab" user "Ref Des/Assembly Bottom")
	)
	(footprint ""
		(layer "B.Cu")
		(at 53.68798 -30.86608 -90)
		(property "Reference" "R260"
			(at 0 0 90)
			(layer "B.SilkS")
			(hide yes)
			(effects
				(font
					(size 1.27 1.27)
				)
				(justify mirror)
			)
		)
		(property "Value" ""
			(at 0 0 90)
			(layer "B.Fab")
			(effects
				(font
					(size 1.27 1.27)
				)
				(justify mirror)
			)
		)
		(duplicate_pad_numbers_are_jumpers no)
		(fp_line
			(start -0.7874 0.4064)
			(end 0.7874 0.4064)
			(stroke
				(width 0.1524)
				(type default)
			)
			(layer "B.SilkS")
		)
		(fp_line
			(start 0.7874 0.4064)
			(end 0.7874 -0.4064)
			(stroke
				(width 0.1524)
				(type default)
			)
			(layer "B.SilkS")
		)
		(fp_line
			(start -0.7874 -0.4064)
			(end -0.7874 0.4064)
			(stroke
				(width 0.1524)
				(type default)
			)
			(layer "B.SilkS")
		)
		(fp_line
			(start 0.7874 -0.4064)
			(end -0.7874 -0.4064)
			(stroke
				(width 0.1524)
				(type default)
			)
			(layer "B.SilkS")
		)
		(fp_line
			(start -0.67945 0.3048)
			(end -0.120396 0.3048)
			(stroke
				(width 0.1)
				(type default)
			)
			(layer "B.Fab")
		)
		(fp_line
			(start -0.120396 0.3048)
			(end -0.120396 0.2794)
			(stroke
				(width 0.1)
				(type default)
			)
			(layer "B.Fab")
		)
		(fp_line
			(start 0.12065 0.3048)
			(end 0.67945 0.3048)
			(stroke
				(width 0.1)
				(type default)
			)
			(layer "B.Fab")
		)
		(fp_line
			(start 0.67945 0.3048)
			(end 0.67945 -0.305054)
			(stroke
				(width 0.1)
				(type default)
			)
			(layer "B.Fab")
		)
		(fp_line
			(start -0.120396 0.2794)
			(end 0.12065 0.2794)
			(stroke
				(width 0.1)
				(type default)
			)
			(layer "B.Fab")
		)
		(fp_line
			(start 0.12065 0.2794)
			(end 0.12065 0.3048)
			(stroke
				(width 0.1)
				(type default)
			)
			(layer "B.Fab")
		)
		(fp_line
			(start -0.12065 -0.2794)
			(end -0.12065 -0.3048)
			(stroke
				(width 0.1)
				(type default)
			)
			(layer "B.Fab")
		)
		(fp_line
			(start 0.12065 -0.2794)
			(end -0.12065 -0.2794)
			(stroke
				(width 0.1)
				(type default)
			)
			(layer "B.Fab")
		)
		(fp_line
			(start -0.67945 -0.3048)
			(end -0.67945 0.3048)
			(stroke
				(width 0.1)
				(type default)
			)
			(layer "B.Fab")
		)
		(fp_line
			(start -0.12065 -0.3048)
			(end -0.67945 -0.3048)
			(stroke
				(width 0.1)
				(type default)
			)
			(layer "B.Fab")
		)
		(fp_line
			(start 0.12065 -0.305054)
			(end 0.12065 -0.2794)
			(stroke
				(width 0.1)
				(type default)
			)
			(layer "B.Fab")
		)
		(fp_line
			(start 0.67945 -0.305054)
			(end 0.12065 -0.305054)
			(stroke
				(width 0.1)
				(type default)
			)
			(layer "B.Fab")
		)
		(pad "1" smd circle
			(at 0.40005 0 90)
			(size 0 0)
			(layers "B.Cu" "B.Mask" "B.Paste")
			(net "P3V3_AUX")
		)
		(pad "2" smd circle
			(at -0.40005 0 90)
			(size 0 0)
			(layers "B.Cu" "B.Mask" "B.Paste")
			(net "SMB_BMC_MM9_SCL")
		)
	)
	(footprint ""
		(layer "B.Cu")
		(at 78.723744 -35.540188 -90)
		(property "Reference" "R334"
			(at 0 0 90)
			(layer "B.SilkS")
			(hide yes)
			(effects
				(font
					(size 1.27 1.27)
				)
				(justify mirror)
			)
		)
		(property "Value" ""
			(at 0 0 90)
			(layer "B.Fab")
			(effects
				(font
					(size 1.27 1.27)
				)
				(justify mirror)
			)
		)
		(duplicate_pad_numbers_are_jumpers no)
		(fp_line
			(start -0.7874 0.4064)
			(end 0.7874 0.4064)
			(stroke
				(width 0.1524)
				(type default)
			)
			(layer "B.SilkS")
		)
		(fp_line
			(start 0.7874 0.4064)
			(end 0.7874 -0.4064)
			(stroke
				(width 0.1524)
				(type default)
			)
			(layer "B.SilkS")
		)
		(fp_line
			(start -0.7874 -0.4064)
			(end -0.7874 0.4064)
			(stroke
				(width 0.1524)
				(type default)
			)
			(layer "B.SilkS")
		)
		(fp_line
			(start 0.7874 -0.4064)
			(end -0.7874 -0.4064)
			(stroke
				(width 0.1524)
				(type default)
			)
			(layer "B.SilkS")
		)
		(fp_line
			(start -0.67945 0.3048)
			(end -0.120396 0.3048)
			(stroke
				(width 0.1)
				(type default)
			)
			(layer "B.Fab")
		)
		(fp_line
			(start -0.120396 0.3048)
			(end -0.120396 0.2794)
			(stroke
				(width 0.1)
				(type default)
			)
			(layer "B.Fab")
		)
		(fp_line
			(start 0.12065 0.3048)
			(end 0.67945 0.3048)
			(stroke
				(width 0.1)
				(type default)
			)
			(layer "B.Fab")
		)
		(fp_line
			(start 0.67945 0.3048)
			(end 0.67945 -0.305054)
			(stroke
				(width 0.1)
				(type default)
			)
			(layer "B.Fab")
		)
		(fp_line
			(start -0.120396 0.2794)
			(end 0.12065 0.2794)
			(stroke
				(width 0.1)
				(type default)
			)
			(layer "B.Fab")
		)
		(fp_line
			(start 0.12065 0.2794)
			(end 0.12065 0.3048)
			(stroke
				(width 0.1)
				(type default)
			)
			(layer "B.Fab")
		)
		(fp_line
			(start -0.12065 -0.2794)
			(end -0.12065 -0.3048)
			(stroke
				(width 0.1)
				(type default)
			)
			(layer "B.Fab")
		)
		(fp_line
			(start 0.12065 -0.2794)
			(end -0.12065 -0.2794)
			(stroke
				(width 0.1)
				(type default)
			)
			(layer "B.Fab")
		)
		(fp_line
			(start -0.67945 -0.3048)
			(end -0.67945 0.3048)
			(stroke
				(width 0.1)
				(type default)
			)
			(layer "B.Fab")
		)
		(fp_line
			(start -0.12065 -0.3048)
			(end -0.67945 -0.3048)
			(stroke
				(width 0.1)
				(type default)
			)
			(layer "B.Fab")
		)
		(fp_line
			(start 0.12065 -0.305054)
			(end 0.12065 -0.2794)
			(stroke
				(width 0.1)
				(type default)
			)
			(layer "B.Fab")
		)
		(fp_line
			(start 0.67945 -0.305054)
			(end 0.12065 -0.305054)
			(stroke
				(width 0.1)
				(type default)
			)
			(layer "B.Fab")
		)
		(pad "1" smd circle
			(at 0.40005 0 90)
			(size 0 0)
			(layers "B.Cu" "B.Mask" "B.Paste")
			(net "GND")
		)
		(pad "2" smd circle
			(at -0.40005 0 90)
			(size 0 0)
			(layers "B.Cu" "B.Mask" "B.Paste")
			(net "M_BMC_DDR4_MA<8>")
		)
	)
)
